(kicad_pcb
	(version 20260206)
	(generator "pcbnew")
	(generator_version "10.0")
	(general
		(thickness 1.6)
		(legacy_teardrops no)
	)
	(paper "A4")
	(title_block
		(title "01162023_DA0F0TEBIF0_F0T_Expander_BD_F_brd_V02_OCP.brd")
		(comment 1 "Grand Teton / footprints 492-498 of 9728")
	)
	(layers
		(0 "F.Cu" signal "TOP")
		(4 "In1.Cu" signal "GND")
		(6 "In2.Cu" signal "VCC")
		(8 "In3.Cu" signal "VCC1")
		(10 "In4.Cu" signal "GND1")
		(12 "In5.Cu" signal "IN1")
		(14 "In6.Cu" signal "GND2")
		(16 "In7.Cu" signal "IN2")
		(18 "In8.Cu" signal "GND3")
		(20 "In9.Cu" signal "IN3")
		(22 "In10.Cu" signal "GND4")
		(24 "In11.Cu" signal "IN4")
		(26 "In12.Cu" signal "GND5")
		(28 "In13.Cu" signal "IN5")
		(30 "In14.Cu" signal "GND6")
		(32 "In15.Cu" signal "IN6")
		(34 "In16.Cu" signal "GND7")
		(2 "B.Cu" signal "BOTTOM")
		(9 "F.Adhes" user "F.Adhesive")
		(11 "B.Adhes" user "B.Adhesive")
		(13 "F.Paste" user "Package Geometry/Pastemask Top")
		(15 "B.Paste" user "Package Geometry/Pastemask Bottom")
		(5 "F.SilkS" user "Ref Des/Silkscreen Top")
		(7 "B.SilkS" user "Ref Des/Silkscreen Bottom")
		(1 "F.Mask" user "Board Geometry/Soldermask Top")
		(3 "B.Mask" user "Board Geometry/Soldermask Bottom")
		(17 "Dwgs.User" user "User.Drawings")
		(19 "Cmts.User" user "User.Comments")
		(21 "Eco1.User" user "User.Eco1")
		(23 "Eco2.User" user "User.Eco2")
		(25 "Edge.Cuts" user "Board Geometry/Outline")
		(27 "Margin" user)
		(31 "F.CrtYd" user "Package Geometry/Place Bound Top")
		(29 "B.CrtYd" user "Package Geometry/Place Bound Bottom")
		(35 "F.Fab" user "Ref Des/Assembly Top")
		(33 "B.Fab" user "Ref Des/Assembly Bottom")
	)
	(footprint ""
		(layer "F.Cu")
		(at 276.922484 -44.341542 90)
		(property "Reference" "R613"
			(at 0 0 90)
			(layer "F.SilkS")
			(hide yes)
			(effects
				(font
					(size 1.27 1.27)
				)
			)
		)
		(property "Value" ""
			(at 0 0 90)
			(layer "F.Fab")
			(effects
				(font
					(size 1.27 1.27)
				)
			)
		)
		(duplicate_pad_numbers_are_jumpers no)
		(fp_line
			(start 0.7874 -0.4064)
			(end 0.7874 0.4064)
			(stroke
				(width 0.1524)
				(type default)
			)
			(layer "F.SilkS")
		)
		(fp_line
			(start -0.7874 -0.4064)
			(end 0.7874 -0.4064)
			(stroke
				(width 0.1524)
				(type default)
			)
			(layer "F.SilkS")
		)
		(fp_line
			(start 0.7874 0.4064)
			(end -0.7874 0.4064)
			(stroke
				(width 0.1524)
				(type default)
			)
			(layer "F.SilkS")
		)
		(fp_line
			(start -0.7874 0.4064)
			(end -0.7874 -0.4064)
			(stroke
				(width 0.1524)
				(type default)
			)
			(layer "F.SilkS")
		)
		(fp_line
			(start -0.12065 -0.305054)
			(end -0.12065 -0.2794)
			(stroke
				(width 0.1)
				(type default)
			)
			(layer "F.Fab")
		)
		(fp_line
			(start -0.67945 -0.305054)
			(end -0.12065 -0.305054)
			(stroke
				(width 0.1)
				(type default)
			)
			(layer "F.Fab")
		)
		(fp_line
			(start 0.67945 -0.3048)
			(end 0.67945 0.3048)
			(stroke
				(width 0.1)
				(type default)
			)
			(layer "F.Fab")
		)
		(fp_line
			(start 0.12065 -0.3048)
			(end 0.67945 -0.3048)
			(stroke
				(width 0.1)
				(type default)
			)
			(layer "F.Fab")
		)
		(fp_line
			(start 0.12065 -0.2794)
			(end 0.12065 -0.3048)
			(stroke
				(width 0.1)
				(type default)
			)
			(layer "F.Fab")
		)
		(fp_line
			(start -0.12065 -0.2794)
			(end 0.12065 -0.2794)
			(stroke
				(width 0.1)
				(type default)
			)
			(layer "F.Fab")
		)
		(fp_line
			(start 0.120396 0.2794)
			(end -0.12065 0.2794)
			(stroke
				(width 0.1)
				(type default)
			)
			(layer "F.Fab")
		)
		(fp_line
			(start -0.12065 0.2794)
			(end -0.12065 0.3048)
			(stroke
				(width 0.1)
				(type default)
			)
			(layer "F.Fab")
		)
		(fp_line
			(start 0.67945 0.3048)
			(end 0.120396 0.3048)
			(stroke
				(width 0.1)
				(type default)
			)
			(layer "F.Fab")
		)
		(fp_line
			(start 0.120396 0.3048)
			(end 0.120396 0.2794)
			(stroke
				(width 0.1)
				(type default)
			)
			(layer "F.Fab")
		)
		(fp_line
			(start -0.12065 0.3048)
			(end -0.67945 0.3048)
			(stroke
				(width 0.1)
				(type default)
			)
			(layer "F.Fab")
		)
		(fp_line
			(start -0.67945 0.3048)
			(end -0.67945 -0.305054)
			(stroke
				(width 0.1)
				(type default)
			)
			(layer "F.Fab")
		)
		(pad "1" smd circle
			(at -0.40005 0 90)
			(size 0 0)
			(layers "F.Cu" "F.Mask" "F.Paste")
			(net "P12V_SSD9")
		)
		(pad "2" smd circle
			(at 0.40005 0 90)
			(size 0 0)
			(layers "F.Cu" "F.Mask" "F.Paste")
			(net "P12V_SSD9_VIN_N")
		)
	)
	(footprint ""
		(layer "F.Cu")
		(at 283.623766 -167.742108)
		(property "Reference" "C933"
			(at 0 0 0)
			(layer "F.SilkS")
			(hide yes)
			(effects
				(font
					(size 1.27 1.27)
				)
			)
		)
		(property "Value" ""
			(at 0 0 0)
			(layer "F.Fab")
			(effects
				(font
					(size 1.27 1.27)
				)
			)
		)
		(duplicate_pad_numbers_are_jumpers no)
		(fp_line
			(start -0.7874 -0.4064)
			(end 0.7874 -0.4064)
			(stroke
				(width 0.1524)
				(type default)
			)
			(layer "F.SilkS")
		)
		(fp_line
			(start -0.7874 0.4064)
			(end -0.7874 -0.4064)
			(stroke
				(width 0.1524)
				(type default)
			)
			(layer "F.SilkS")
		)
		(fp_line
			(start 0.7874 -0.4064)
			(end 0.7874 0.4064)
			(stroke
				(width 0.1524)
				(type default)
			)
			(layer "F.SilkS")
		)
		(fp_line
			(start 0.7874 0.4064)
			(end -0.7874 0.4064)
			(stroke
				(width 0.1524)
				(type default)
			)
			(layer "F.SilkS")
		)
		(fp_line
			(start -0.67945 -0.305054)
			(end -0.12065 -0.305054)
			(stroke
				(width 0.1)
				(type default)
			)
			(layer "F.Fab")
		)
		(fp_line
			(start -0.67945 0.3048)
			(end -0.67945 -0.305054)
			(stroke
				(width 0.1)
				(type default)
			)
			(layer "F.Fab")
		)
		(fp_line
			(start -0.12065 -0.305054)
			(end -0.12065 -0.2794)
			(stroke
				(width 0.1)
				(type default)
			)
			(layer "F.Fab")
		)
		(fp_line
			(start -0.12065 -0.2794)
			(end 0.12065 -0.2794)
			(stroke
				(width 0.1)
				(type default)
			)
			(layer "F.Fab")
		)
		(fp_line
			(start -0.12065 0.2794)
			(end -0.12065 0.3048)
			(stroke
				(width 0.1)
				(type default)
			)
			(layer "F.Fab")
		)
		(fp_line
			(start -0.12065 0.3048)
			(end -0.67945 0.3048)
			(stroke
				(width 0.1)
				(type default)
			)
			(layer "F.Fab")
		)
		(fp_line
			(start 0.120396 0.2794)
			(end -0.12065 0.2794)
			(stroke
				(width 0.1)
				(type default)
			)
			(layer "F.Fab")
		)
		(fp_line
			(start 0.120396 0.3048)
			(end 0.120396 0.2794)
			(stroke
				(width 0.1)
				(type default)
			)
			(layer "F.Fab")
		)
		(fp_line
			(start 0.12065 -0.3048)
			(end 0.67945 -0.3048)
			(stroke
				(width 0.1)
				(type default)
			)
			(layer "F.Fab")
		)
		(fp_line
			(start 0.12065 -0.2794)
			(end 0.12065 -0.3048)
			(stroke
				(width 0.1)
				(type default)
			)
			(layer "F.Fab")
		)
		(fp_line
			(start 0.67945 -0.3048)
			(end 0.67945 0.3048)
			(stroke
				(width 0.1)
				(type default)
			)
			(layer "F.Fab")
		)
		(fp_line
			(start 0.67945 0.3048)
			(end 0.120396 0.3048)
			(stroke
				(width 0.1)
				(type default)
			)
			(layer "F.Fab")
		)
		(pad "1" smd circle
			(at -0.40005 0)
			(size 0 0)
			(layers "F.Cu" "F.Mask" "F.Paste")
			(net "P3V3_AUX")
		)
		(pad "2" smd circle
			(at 0.40005 0)
			(size 0 0)
			(layers "F.Cu" "F.Mask" "F.Paste")
			(net "GND")
		)
	)
	(footprint ""
		(layer "F.Cu")
		(at 427.923452 -343.952322 90)
		(property "Reference" "C808"
			(at 0 0 90)
			(layer "F.SilkS")
			(hide yes)
			(effects
				(font
					(size 1.27 1.27)
				)
			)
		)
		(property "Value" ""
			(at 0 0 90)
			(layer "F.Fab")
			(effects
				(font
					(size 1.27 1.27)
				)
			)
		)
		(duplicate_pad_numbers_are_jumpers no)
		(fp_line
			(start 0.299974 -0.150114)
			(end 0.299974 0.150114)
			(stroke
				(width 0.1)
				(type default)
			)
			(layer "F.Fab")
		)
		(fp_line
			(start -0.299974 -0.150114)
			(end 0.299974 -0.150114)
			(stroke
				(width 0.1)
				(type default)
			)
			(layer "F.Fab")
		)
		(fp_line
			(start 0.299974 0.150114)
			(end -0.299974 0.150114)
			(stroke
				(width 0.1)
				(type default)
			)
			(layer "F.Fab")
		)
		(fp_line
			(start -0.299974 0.150114)
			(end -0.299974 -0.150114)
			(stroke
				(width 0.1)
				(type default)
			)
			(layer "F.Fab")
		)
		(pad "1" smd rect
			(at -0.2667 0 90)
			(size 0.3048 0.381)
			(layers "F.Cu" "F.Mask" "F.Paste")
			(net "P5E_PEX3_STN7_TX_DP<120>")
		)
		(pad "2" smd rect
			(at 0.2667 0 90)
			(size 0.3048 0.381)
			(layers "F.Cu" "F.Mask" "F.Paste")
			(net "P5E_PEX3_STN7_TX_C_DP<120>")
		)
	)
	(footprint ""
		(layer "F.Cu")
		(at 221.081854 -257.975862 -90)
		(property "Reference" "R6491"
			(at 0 0 270)
			(layer "F.SilkS")
			(hide yes)
			(effects
				(font
					(size 1.27 1.27)
				)
			)
		)
		(property "Value" ""
			(at 0 0 270)
			(layer "F.Fab")
			(effects
				(font
					(size 1.27 1.27)
				)
			)
		)
		(duplicate_pad_numbers_are_jumpers no)
		(fp_line
			(start -0.7874 0.4064)
			(end -0.7874 -0.4064)
			(stroke
				(width 0.1524)
				(type default)
			)
			(layer "F.SilkS")
		)
		(fp_line
			(start 0.7874 0.4064)
			(end -0.7874 0.4064)
			(stroke
				(width 0.1524)
				(type default)
			)
			(layer "F.SilkS")
		)
		(fp_line
			(start -0.7874 -0.4064)
			(end 0.7874 -0.4064)
			(stroke
				(width 0.1524)
				(type default)
			)
			(layer "F.SilkS")
		)
		(fp_line
			(start 0.7874 -0.4064)
			(end 0.7874 0.4064)
			(stroke
				(width 0.1524)
				(type default)
			)
			(layer "F.SilkS")
		)
		(fp_line
			(start -0.67945 0.3048)
			(end -0.67945 -0.305054)
			(stroke
				(width 0.1)
				(type default)
			)
			(layer "F.Fab")
		)
		(fp_line
			(start -0.12065 0.3048)
			(end -0.67945 0.3048)
			(stroke
				(width 0.1)
				(type default)
			)
			(layer "F.Fab")
		)
		(fp_line
			(start 0.120396 0.3048)
			(end 0.120396 0.2794)
			(stroke
				(width 0.1)
				(type default)
			)
			(layer "F.Fab")
		)
		(fp_line
			(start 0.67945 0.3048)
			(end 0.120396 0.3048)
			(stroke
				(width 0.1)
				(type default)
			)
			(layer "F.Fab")
		)
		(fp_line
			(start -0.12065 0.2794)
			(end -0.12065 0.3048)
			(stroke
				(width 0.1)
				(type default)
			)
			(layer "F.Fab")
		)
		(fp_line
			(start 0.120396 0.2794)
			(end -0.12065 0.2794)
			(stroke
				(width 0.1)
				(type default)
			)
			(layer "F.Fab")
		)
		(fp_line
			(start -0.12065 -0.2794)
			(end 0.12065 -0.2794)
			(stroke
				(width 0.1)
				(type default)
			)
			(layer "F.Fab")
		)
		(fp_line
			(start 0.12065 -0.2794)
			(end 0.12065 -0.3048)
			(stroke
				(width 0.1)
				(type default)
			)
			(layer "F.Fab")
		)
		(fp_line
			(start 0.12065 -0.3048)
			(end 0.67945 -0.3048)
			(stroke
				(width 0.1)
				(type default)
			)
			(layer "F.Fab")
		)
		(fp_line
			(start 0.67945 -0.3048)
			(end 0.67945 0.3048)
			(stroke
				(width 0.1)
				(type default)
			)
			(layer "F.Fab")
		)
		(fp_line
			(start -0.67945 -0.305054)
			(end -0.12065 -0.305054)
			(stroke
				(width 0.1)
				(type default)
			)
			(layer "F.Fab")
		)
		(fp_line
			(start -0.12065 -0.305054)
			(end -0.12065 -0.2794)
			(stroke
				(width 0.1)
				(type default)
			)
			(layer "F.Fab")
		)
		(pad "1" smd circle
			(at -0.40005 0 270)
			(size 0 0)
			(layers "F.Cu" "F.Mask" "F.Paste")
			(net "P1V25_SERDES_VDDPLL_PEX1")
		)
		(pad "2" smd circle
			(at 0.40005 0 270)
			(size 0 0)
			(layers "F.Cu" "F.Mask" "F.Paste")
			(net "P1V25_SERDES_VDDPLL_PEX1_C0")
		)
	)
	(footprint ""
		(layer "F.Cu")
		(at 210.161886 -233.881422 -90)
		(property "Reference" "R1543"
			(at 0 0 270)
			(layer "F.SilkS")
			(hide yes)
			(effects
				(font
					(size 1.27 1.27)
				)
			)
		)
		(property "Value" ""
			(at 0 0 270)
			(layer "F.Fab")
			(effects
				(font
					(size 1.27 1.27)
				)
			)
		)
		(duplicate_pad_numbers_are_jumpers no)
		(fp_line
			(start -0.7874 0.4064)
			(end -0.7874 -0.4064)
			(stroke
				(width 0.1524)
				(type default)
			)
			(layer "F.SilkS")
		)
		(fp_line
			(start 0.7874 0.4064)
			(end -0.7874 0.4064)
			(stroke
				(width 0.1524)
				(type default)
			)
			(layer "F.SilkS")
		)
		(fp_line
			(start -0.7874 -0.4064)
			(end 0.7874 -0.4064)
			(stroke
				(width 0.1524)
				(type default)
			)
			(layer "F.SilkS")
		)
		(fp_line
			(start 0.7874 -0.4064)
			(end 0.7874 0.4064)
			(stroke
				(width 0.1524)
				(type default)
			)
			(layer "F.SilkS")
		)
		(fp_line
			(start -0.67945 0.3048)
			(end -0.67945 -0.305054)
			(stroke
				(width 0.1)
				(type default)
			)
			(layer "F.Fab")
		)
		(fp_line
			(start -0.12065 0.3048)
			(end -0.67945 0.3048)
			(stroke
				(width 0.1)
				(type default)
			)
			(layer "F.Fab")
		)
		(fp_line
			(start 0.120396 0.3048)
			(end 0.120396 0.2794)
			(stroke
				(width 0.1)
				(type default)
			)
			(layer "F.Fab")
		)
		(fp_line
			(start 0.67945 0.3048)
			(end 0.120396 0.3048)
			(stroke
				(width 0.1)
				(type default)
			)
			(layer "F.Fab")
		)
		(fp_line
			(start -0.12065 0.2794)
			(end -0.12065 0.3048)
			(stroke
				(width 0.1)
				(type default)
			)
			(layer "F.Fab")
		)
		(fp_line
			(start 0.120396 0.2794)
			(end -0.12065 0.2794)
			(stroke
				(width 0.1)
				(type default)
			)
			(layer "F.Fab")
		)
		(fp_line
			(start -0.12065 -0.2794)
			(end 0.12065 -0.2794)
			(stroke
				(width 0.1)
				(type default)
			)
			(layer "F.Fab")
		)
		(fp_line
			(start 0.12065 -0.2794)
			(end 0.12065 -0.3048)
			(stroke
				(width 0.1)
				(type default)
			)
			(layer "F.Fab")
		)
		(fp_line
			(start 0.12065 -0.3048)
			(end 0.67945 -0.3048)
			(stroke
				(width 0.1)
				(type default)
			)
			(layer "F.Fab")
		)
		(fp_line
			(start 0.67945 -0.3048)
			(end 0.67945 0.3048)
			(stroke
				(width 0.1)
				(type default)
			)
			(layer "F.Fab")
		)
		(fp_line
			(start -0.67945 -0.305054)
			(end -0.12065 -0.305054)
			(stroke
				(width 0.1)
				(type default)
			)
			(layer "F.Fab")
		)
		(fp_line
			(start -0.12065 -0.305054)
			(end -0.12065 -0.2794)
			(stroke
				(width 0.1)
				(type default)
			)
			(layer "F.Fab")
		)
		(pad "1" smd circle
			(at -0.40005 0 270)
			(size 0 0)
			(layers "F.Cu" "F.Mask" "F.Paste")
			(net "SMB_PEX_LS_R_SCL")
		)
		(pad "2" smd circle
			(at 0.40005 0 270)
			(size 0 0)
			(layers "F.Cu" "F.Mask" "F.Paste")
			(net "SMB_PEX1_SCL")
		)
	)
	(footprint ""
		(layer "F.Cu")
		(at 397.120618 -70.307454 90)
		(property "Reference" "PC889"
			(at 0 0 90)
			(layer "F.SilkS")
			(hide yes)
			(effects
				(font
					(size 1.27 1.27)
				)
			)
		)
		(property "Value" ""
			(at 0 0 90)
			(layer "F.Fab")
			(effects
				(font
					(size 1.27 1.27)
				)
			)
		)
		(duplicate_pad_numbers_are_jumpers no)
		(fp_line
			(start 0.7874 -0.4064)
			(end 0.7874 0.4064)
			(stroke
				(width 0.1524)
				(type default)
			)
			(layer "F.SilkS")
		)
		(fp_line
			(start -0.7874 -0.4064)
			(end 0.7874 -0.4064)
			(stroke
				(width 0.1524)
				(type default)
			)
			(layer "F.SilkS")
		)
		(fp_line
			(start 0.7874 0.4064)
			(end -0.7874 0.4064)
			(stroke
				(width 0.1524)
				(type default)
			)
			(layer "F.SilkS")
		)
		(fp_line
			(start -0.7874 0.4064)
			(end -0.7874 -0.4064)
			(stroke
				(width 0.1524)
				(type default)
			)
			(layer "F.SilkS")
		)
		(fp_line
			(start -0.12065 -0.305054)
			(end -0.12065 -0.2794)
			(stroke
				(width 0.1)
				(type default)
			)
			(layer "F.Fab")
		)
		(fp_line
			(start -0.67945 -0.305054)
			(end -0.12065 -0.305054)
			(stroke
				(width 0.1)
				(type default)
			)
			(layer "F.Fab")
		)
		(fp_line
			(start 0.67945 -0.3048)
			(end 0.67945 0.3048)
			(stroke
				(width 0.1)
				(type default)
			)
			(layer "F.Fab")
		)
		(fp_line
			(start 0.12065 -0.3048)
			(end 0.67945 -0.3048)
			(stroke
				(width 0.1)
				(type default)
			)
			(layer "F.Fab")
		)
		(fp_line
			(start 0.12065 -0.2794)
			(end 0.12065 -0.3048)
			(stroke
				(width 0.1)
				(type default)
			)
			(layer "F.Fab")
		)
		(fp_line
			(start -0.12065 -0.2794)
			(end 0.12065 -0.2794)
			(stroke
				(width 0.1)
				(type default)
			)
			(layer "F.Fab")
		)
		(fp_line
			(start 0.120396 0.2794)
			(end -0.12065 0.2794)
			(stroke
				(width 0.1)
				(type default)
			)
			(layer "F.Fab")
		)
		(fp_line
			(start -0.12065 0.2794)
			(end -0.12065 0.3048)
			(stroke
				(width 0.1)
				(type default)
			)
			(layer "F.Fab")
		)
		(fp_line
			(start 0.67945 0.3048)
			(end 0.120396 0.3048)
			(stroke
				(width 0.1)
				(type default)
			)
			(layer "F.Fab")
		)
		(fp_line
			(start 0.120396 0.3048)
			(end 0.120396 0.2794)
			(stroke
				(width 0.1)
				(type default)
			)
			(layer "F.Fab")
		)
		(fp_line
			(start -0.12065 0.3048)
			(end -0.67945 0.3048)
			(stroke
				(width 0.1)
				(type default)
			)
			(layer "F.Fab")
		)
		(fp_line
			(start -0.67945 0.3048)
			(end -0.67945 -0.305054)
			(stroke
				(width 0.1)
				(type default)
			)
			(layer "F.Fab")
		)
		(pad "1" smd circle
			(at -0.40005 0 90)
			(size 0 0)
			(layers "F.Cu" "F.Mask" "F.Paste")
			(net "P12V_AUX")
		)
		(pad "2" smd circle
			(at 0.40005 0 90)
			(size 0 0)
			(layers "F.Cu" "F.Mask" "F.Paste")
			(net "GND")
		)
	)
	(footprint ""
		(layer "F.Cu")
		(at 407.295096 -104.830372 180)
		(property "Reference" "R377"
			(at 0 0 180)
			(layer "F.SilkS")
			(hide yes)
			(effects
				(font
					(size 1.27 1.27)
				)
			)
		)
		(property "Value" ""
			(at 0 0 180)
			(layer "F.Fab")
			(effects
				(font
					(size 1.27 1.27)
				)
			)
		)
		(duplicate_pad_numbers_are_jumpers no)
		(fp_line
			(start 0.7874 0.4064)
			(end -0.7874 0.4064)
			(stroke
				(width 0.1524)
				(type default)
			)
			(layer "F.SilkS")
		)
		(fp_line
			(start 0.7874 -0.4064)
			(end 0.7874 0.4064)
			(stroke
				(width 0.1524)
				(type default)
			)
			(layer "F.SilkS")
		)
		(fp_line
			(start -0.7874 0.4064)
			(end -0.7874 -0.4064)
			(stroke
				(width 0.1524)
				(type default)
			)
			(layer "F.SilkS")
		)
		(fp_line
			(start -0.7874 -0.4064)
			(end 0.7874 -0.4064)
			(stroke
				(width 0.1524)
				(type default)
			)
			(layer "F.SilkS")
		)
		(fp_line
			(start 0.67945 0.3048)
			(end 0.120396 0.3048)
			(stroke
				(width 0.1)
				(type default)
			)
			(layer "F.Fab")
		)
		(fp_line
			(start 0.67945 -0.3048)
			(end 0.67945 0.3048)
			(stroke
				(width 0.1)
				(type default)
			)
			(layer "F.Fab")
		)
		(fp_line
			(start 0.12065 -0.2794)
			(end 0.12065 -0.3048)
			(stroke
				(width 0.1)
				(type default)
			)
			(layer "F.Fab")
		)
		(fp_line
			(start 0.12065 -0.3048)
			(end 0.67945 -0.3048)
			(stroke
				(width 0.1)
				(type default)
			)
			(layer "F.Fab")
		)
		(fp_line
			(start 0.120396 0.3048)
			(end 0.120396 0.2794)
			(stroke
				(width 0.1)
				(type default)
			)
			(layer "F.Fab")
		)
		(fp_line
			(start 0.120396 0.2794)
			(end -0.12065 0.2794)
			(stroke
				(width 0.1)
				(type default)
			)
			(layer "F.Fab")
		)
		(fp_line
			(start -0.12065 0.3048)
			(end -0.67945 0.3048)
			(stroke
				(width 0.1)
				(type default)
			)
			(layer "F.Fab")
		)
		(fp_line
			(start -0.12065 0.2794)
			(end -0.12065 0.3048)
			(stroke
				(width 0.1)
				(type default)
			)
			(layer "F.Fab")
		)
		(fp_line
			(start -0.12065 -0.2794)
			(end 0.12065 -0.2794)
			(stroke
				(width 0.1)
				(type default)
			)
			(layer "F.Fab")
		)
		(fp_line
			(start -0.12065 -0.305054)
			(end -0.12065 -0.2794)
			(stroke
				(width 0.1)
				(type default)
			)
			(layer "F.Fab")
		)
		(fp_line
			(start -0.67945 0.3048)
			(end -0.67945 -0.305054)
			(stroke
				(width 0.1)
				(type default)
			)
			(layer "F.Fab")
		)
		(fp_line
			(start -0.67945 -0.305054)
			(end -0.12065 -0.305054)
			(stroke
				(width 0.1)
				(type default)
			)
			(layer "F.Fab")
		)
		(pad "1" smd circle
			(at -0.40005 0 180)
			(size 0 0)
			(layers "F.Cu" "F.Mask" "F.Paste")
			(net "CLK_50M_NIC7_RBT_REF")
		)
		(pad "2" smd circle
			(at 0.40005 0 180)
			(size 0 0)
			(layers "F.Cu" "F.Mask" "F.Paste")
			(net "GND")
		)
	)
)
